1
1
2
2
3
3
4
4
5
5
6
6
D D
C C
B B
A A
timingcard.com
1SHEET OF 8
Cannot open file 
C:\Users\<user>\Desktop\Ti
mecard 
Logo\TIMECARD.jpg.  
File does not exist.
REV DATEP3 09/14/21
1
2
3
GND4 VCC8
7
6
5
U8
NC7WV125K8X
GND
1
2
3
J1
1909763-1
5
1
2
3
4
AN1
RF2-49B-T-00-50-G-HDW
GND
R25
49.9R
ANT1_OUT
R14
4.7K
R15
4.7K
+3.3V +3.3V
ANT1_IN
C26
0.1uF
GNDGND
+3.3V
1
2 3
4
D1
8240136
1
2
3
GND4 VCC8
7
6
5
U11
NC7WV125K8X
GND
1
2
3
J3
1909763-1
5
1
2
3
4
AN3
RF2-49B-T-00-50-G-HDW
GND
R28
49.9R
ANT3_OUT
R16
4.7K
R17
4.7K
+3.3V +3.3V
ANT3_IN
C27
0.1uF
GNDGND
+3.3V
1
2
3
GND4 VCC8
7
6
5
U16
NC7WV125K8X
1
2
3
J4
1909763-1
5
1
2
3
4
AN4
RF2-49B-T-00-50-G-HDW
GND
R34
49.9R
ANT4_OUT
R31
4.7K
R32
4.7K
+3.3V +3.3V
ANT4_IN
C29
0.1uF
GNDGND
+3.3V
1
2
3
GND4 VCC8
7
6
5
U12
NC7WV125K8X
GND
1
2
3
J2
1909763-1
5
1
2
3
4
AN2
RF2-49B-T-00-50-G-HDW
GND
R33
49.9R
ANT2_OUT
R29
4.7K
R30
4.7K
+3.3V +3.3V
ANT2_IN
C28
0.1uF
GNDGND
+3.3V
1
2 3
4
D2
8240136
+3.3V
GND
+3.3V
GND
INPUT/OUTPUT SIGNALS
ANT1_IO_OUT
ANT1_IO_IN
ANT2_IO_OUT
ANT2_IO_IN
ANT3_IO_OUT
ANT3_IO_IN
ANT4_IO_OUT
ANT4_IO_IN
GND
PIAN101 
PIAN102 PIAN103 PIAN104 PIAN105 
COAN1 
PIAN201 
PIAN202 PIAN203 PIAN204 PIAN205 
COAN2 
PIAN301 
PIAN302 PIAN303 PIAN304 PIAN305 
COAN3 
PIAN401 
PIAN402 PIAN403 PIAN404 PIAN405 
COAN4 
PIC2601 
PIC2602 
COC26 
PIC2701 
PIC2702 
COC27 
PIC2801 
PIC2802 COC28 
PIC2901 
PIC2902 COC29 
PID101 PID102 
PID103 PID104 COD1 
PID201 PID202 
PID203 PID204 COD2 
PIJ101 
PIJ102 
PIJ103 
COJ1 
PIJ201 
PIJ202 
PIJ203 
COJ2 
PIJ301 
PIJ302 
PIJ303 
COJ3 
PIJ401 
PIJ402 
PIJ403 
COJ4 
PIR1401 
PIR1402 COR14 
PIR1501 
PIR1502 COR15 
PIR1601 
PIR1602 COR16 
PIR1701 
PIR1702 COR17 
PIR2501 PIR2502 
COR25 
PIR2801 PIR2802 
COR28 
PIR2901 
PIR2902 
COR29 
PIR3001 
PIR3002 
COR30 
PIR3101 
PIR3102 
COR31 
PIR3201 
PIR3202 
COR32 
PIR3301 PIR3302 
COR33 
PIR3401 PIR3402 
COR34 
PIU801 
PIU802 
PIU803 
PIU804 
PIU805 
PIU806 
PIU807 
PIU808 
COU8 
PIU1101 
PIU1102 
PIU1103 
PIU1104 
PIU1105 
PIU1106 
PIU1107 
PIU1108 
COU11 
PIU1201 
PIU1202 
PIU1203 
PIU1204 
PIU1205 
PIU1206 
PIU1207 
PIU1208 
COU12 
PIU1601 
PIU1602 
PIU1603 
PIU1604 
PIU1605 
PIU1606 
PIU1607 
PIU1608 
COU16 



1
1
2
2
3
3
4
4
5
5
6
6
D D
C C
B B
A A
Title
Number RevisionSize
B
Date: 1/27/2023 Sheet   of
File: C:\Users\<user>\02-USER_IO_STATUS.SchDocDrawn By:
+3.3V+3.3V+3.3V+3.3V
LED1 LED2 LED3 LED4
SYSTEM STATUS LEDS
R35
200 OHM
R36
200 OHM
R38
200 OHM
R39
200 OHM
ANODE 1
B2 G3 R4
D13
155124M173200
ANODE 1
B2 G3 R4
D14
155124M173200
ANODE 1
B2 G3 R4
D15
155124M173200
ANODE 1
B2 G3 R4
D16
155124M173200
ANODE 1
B2 G3 R4
D17
155124M173200
ANODE 1
B2 G3 R4
D18
155124M173200
SDB1
AD2
VCC3
GND4
ISET5
SDA6
SCL7 OUT1 8
OUT2 9
OUT3 10
GND11
OUT4 12
OUT5 13
OUT6 14
OUT7 15
OUT8 16
OUT9 17
GND18
OUT10 19
OUT11 20
OUT12 21
OUT13 22
OUT14 23
OUT15 24
GND25 OUT16 26
OUT17 27
OUT18 28EP29
U6
IS32FL3207
+3.3V
IO STATUS LEDS
GNSS 1
GNSS 2
IO 1
IO 2
IO 3
IO 4
C40
0.1uF
C38
1uF
R40
DNI_100k
GNDGND GNDGND
+3.3V
+3.3V
LED DRIVER (0x6E)
SDA
SCL
R41
4.7K
GND
D3
BLUE
D9
BLUE
D10
BLUE
D11
BLUE
R109
4.7K_0402
+3.3V
R110
DNI_4.7K_0402
GND
R108
4.7K_0402
PIC3801 
PIC3802 
COC38 
PIC4001 
PIC4002 
COC40 
PID301 
PID302 
COD3 
PID901 
PID902 
COD9 
PID1001 
PID1002 
COD10 
PID1101 
PID1102 
COD11 
PID1301 
PID1302 
PID1303 
PID1304 
COD13 
PID1401 
PID1402 
PID1403 
PID1404 
COD14 
PID1501 
PID1502 
PID1503 
PID1504 
COD15 
PID1601 
PID1602 
PID1603 
PID1604 
COD16 
PID1701 
PID1702 
PID1703 
PID1704 
COD17 
PID1801 
PID1802 
PID1803 
PID1804 
COD18 
PIR3501 
PIR3502 COR35 
PIR3601 
PIR3602 COR36 
PIR3801 
PIR3802 COR38 
PIR3901 
PIR3902 COR39 
PIR4001 
PIR4002 
COR40 
PIR4101 
PIR4102 
COR41 
PIR10801 
PIR10802 
COR108 
PIR10901 
PIR10902 
COR109 
PIR11001 
PIR11002 COR110 
PIU601 
PIU602 
PIU603 
PIU604 
PIU605 
PIU606 
PIU607 
PIU608 
PIU609 
PIU6010 
PIU6011 
PIU6012 
PIU6013 
PIU6014 
PIU6015 
PIU6016 
PIU6017 
PIU6018 
PIU6019 
PIU6020 
PIU6021 
PIU6022 
PIU6023 
PIU6024 
PIU6025 
PIU6026 
PIU6027 
PIU6028 PIU6029 
COU6 



1
1
2
2
3
3
4
4
5
5
6
6
D D
C C
B B
A A
timingcard.com
*SHEET OF 8
Cannot open file 
C:\Users\<user>\Desktop\Ti
mecard 
Logo\TIMECARD.jpg.  
File does not exist.
REV DATEP3 09/14/21
+12V
GND
+3.3V
GND
10uF
C1
SF-0603S500-2
5.00A
SF-0603S500-2CT-ND
F1
C2
0.1uF
GND
+12V_PCIE
2 1
D12
STPS5L60S
2 1
D19
STPS5L60S
R44
DNI_0_5%_1206
1
2
1
2
J38A
39-30-0040
3
4
3
4
J38B
39-30-0040
VIN+8
VIN-7
A0 2
A1 1
SCL 4
SDA 3VS5
GND 6
U2
INA219BIDR
R7
2mOhm_1%_1206
+12V_SENS
C19
0.1uF_0402
12
C20
10uF_16V_0603
+3.3V
GND GND
+12V_SENS+12V
GND
SCL
SDA
R62 0_1%_0402
R64 0_1%_0402
Address 0x40
CS22
EN26
FB24
PVIN13
PVIN14
PVIN15
PVIN16
PVIN17
PVIN18
PVIN19
VIN27
EPAD29
BST 20
PG 25
SW 4
SW 9
SW 10
SW 11
SW 12
1 of 2
SW 30
U1A
MIC24052YJL-TR
NC3
PVDD1
VDD28
PGND2
PGND5
PGND6
PGND7
PGND8
PGND21
SGND23
2 of 2
U1B
MIC24052YJL-TR
GND
R3
4.7K_0402
GND
R59
2.21_1%_0402
+12V
+3.3V
R2
4.7K_0402
R4
1.21_1%_0402
12
C6
0.1uF_25V_0402
R6
2.21_1%_0402
1 2L1
2.2uH_10A
12
C3
0.1uF_50V_0603
12
C4
1uF_16V_0402
P5V_PVDDP5V_VDDP5V_VDD
R5 1.21_1%_0402
P5V_PVDD
P5V_VDD P5V_PVDD
12
C5
2.2uF_16V_0402
GND
12
C7
DNI_1nF_50V_0402
R9
1.21_1%_0402
GND
12
C11
4.7uF_50V_1206
12
C12
4.7uF_50V_1206
1 2+C10
100uF_16V_2917
12
C9
0.1uF_50V_0603
R60
19.6K_1%_0402
P5V_FB
P5V_FB
R61
2.49K_1%_0402
12
C8
4.7nF_50V_0402
R63
470_1%_0402
GND
P5V_SENSE
R8
2mOhm_1%_1206
12
C15
10uF_16V_0603
1 2+C14
100uF_16V_2917
12
C16
2.2uF_16V_0402
12
C17
1uF_16V_0402
12
C18
0.1uF_25V_0402
12
C13
47uF_16V_1206
GND
VIN+8
VIN-7
A0 2
A1 1
SCL 4
SDA 3VS5
GND 6
U17
INA219BIDR
C21
0.1uF_0402
12
C22
10uF_16V_0603
+3.3V
GND GND
P5V_SENSE
GND
SCL
SDA
R65 0_1%_0402
R66 0_1%_0402
Address 0x41 +3.3V
CS22
EN26
FB24
PVIN13
PVIN14
PVIN15
PVIN16
PVIN17
PVIN18
PVIN19
VIN27
EPAD29
BST 20
PG 25
SW 4
SW 9
SW 10
SW 11
SW 12
1 of 2
SW 30
U18A
MIC24052YJL-TR
NC3
PVDD1
VDD28
PGND2
PGND5
PGND6
PGND7
PGND8
PGND21
SGND23
2 of 2
U18B
MIC24052YJL-TR
GND
R68
4.7K_0402
GND
R74
2.21_1%_0402
+12V
+3.3V
R67
4.7K_0402
R69
1.21_1%_0402
12
C71
0.1uF_25V_0402
R71
2.21_1%_0402
1 2L2
2.2uH_10A
12
C68
0.1uF_50V_0603
12
C69
1uF_16V_0402
P3V3_PVDDP3V3_VDDP3V3_VDD
R70 1.21_1%_0402
P3V3_PVDD
P3V3_VDD
GND
P3V3_PVDD
12
C70
2.2uF_16V_0402
GND
12
C72
DNI_1nF_50V_0402
R73
1.21_1%_0402
GND
12
C76
4.7uF_50V_1206
12
C77
4.7uF_50V_1206
1 2+C75
100uF_16V_2917
12
C74
0.1uF_50V_0603
R75
19.6K_1%_0402
P3V3_FB
P3V3_FB
R76
2.49K_1%_0402
12
C73
4.7nF_50V_0402
GND
P3V3_SENSE
R72
2mOhm_1%_1206
12
C80
10uF_16V_0603
1 2+C79
100uF_16V_2917
12
C81
2.2uF_16V_0402
12
C82
1uF_16V_0402
12
C83
0.1uF_25V_0402
12
C78
47uF_16V_1206
GND
VIN+8
VIN-7
A0 2
A1 1
SCL 4
SDA 3VS5
GND 6
U19
INA219BIDR
C84
0.1uF_0402
12
C85
10uF_16V_0603
+3.3V
GND GND
P3V3_SENSE
GND
SCL
SDA
R79 0_1%_0402
R80 0_1%_0402
Address 0x44 +3.3V
+3.3V
GND
+5.0V
+5.0V
+5.0V
+3.3V
GND
21
D21
SD103AWS-7-F
P5V_PVDD
21
D22
SD103AWS-7-F
P3V3_PVDD
21
D20
SML-LX0603IW-TR
21
D4
SML-LX0603IW-TR
1 2
R77
200_1%_0402
1 2
R1
200_1%_0402
2 1
D23
SMDJ12A
GND
R78
787_1%_0402
PIC101 
PIC102 
COC1 
PIC201 
PIC202 
COC2 
PIC301 
PIC302 
COC3 
PIC401 
PIC402 COC4 
PIC501 
PIC502 COC5 
PIC601 
PIC602 COC6 PIC701 
PIC702 COC7 PIC801 
PIC802 COC8 
PIC901 
PIC902 
COC9 
PIC1001 
PIC1002 
COC10 
PIC1101 
PIC1102 COC11 
PIC1201 
PIC1202 COC12 
PIC1301 
PIC1302 COC13 PIC1401 
PIC1402 
COC14 
PIC1501 
PIC1502 COC15 
PIC1601 
PIC1602 COC16 
PIC1701 
PIC1702 COC17 
PIC1801 
PIC1802 COC18 
PIC1901 
PIC1902 COC19 PIC2001 
PIC2002 COC20 
PIC2101 
PIC2102 COC21 PIC2201 
PIC2202 COC22 
PIC6801 
PIC6802 
COC68 
PIC6901 
PIC6902 COC69 
PIC7001 
PIC7002 COC70 
PIC7101 
PIC7102 COC71 PIC7201 
PIC7202 COC72 PIC7301 
PIC7302 COC73 
PIC7401 
PIC7402 
COC74 PIC7501 
PIC7502 
COC75 
PIC7601 
PIC7602 COC76 
PIC7701 
PIC7702 COC77 
PIC7801 
PIC7802 
COC78 PIC7901 
PIC7902 
COC79 
PIC8001 
PIC8002 COC80 
PIC8101 
PIC8102 COC81 
PIC8201 
PIC8202 COC82 
PIC8301 
PIC8302 COC83 
PIC8401 
PIC8402 COC84 PIC8501 
PIC8502 COC85 
PID401 
PID402 COD4 
PID1201 PID1202 
COD12 
PID1901 PID1902 
COD19 
PID2001 
PID2002 
COD20 
PID2101 PID2102 
COD21 
PID2201 PID2202 
COD22 
PID2301 
PID2302 
COD23 
PIF101 PIF102 
COF1 
PIJ3801 
PIJ3802 
COJ38A 
PIJ3803 
PIJ3804 
COJ38B 
PIL101 PIL102 
COL1 
PIL201 PIL202 
COL2 
PIR101 
PIR102 COR1 
PIR201 
PIR202 
COR2 PIR301 
PIR302 
COR3 
PIR401 PIR402 
COR4 
PIR501 PIR502 
COR5 
PIR601 PIR602 
COR6 
PIR701 PIR702 
COR7 
PIR801 PIR802 
COR8 
PIR901 
PIR902 
COR9 
PIR4401 PIR4402 
COR44 
PIR5901 PIR5902 
COR59 
PIR6001 
PIR6002 
COR60 
PIR6101 
PIR6102 
COR61 
PIR6201 PIR6202 
COR62 
PIR6301 
PIR6302 
COR63 
PIR6401 PIR6402 
COR64 
PIR6501 PIR6502 
COR65 
PIR6601 PIR6602 
COR66 
PIR6701 
PIR6702 
COR67 PIR6801 
PIR6802 
COR68 
PIR6901 PIR6902 
COR69 
PIR7001 PIR7002 
COR70 
PIR7101 PIR7102 
COR71 
PIR7201 PIR7202 
COR72 
PIR7301 
PIR7302 
COR73 
PIR7401 PIR7402 
COR74 
PIR7501 
PIR7502 
COR75 
PIR7601 
PIR7602 
COR76 
PIR7701 
PIR7702 COR77 
PIR7801 
PIR7802 
COR78 
PIR7901 PIR7902 
COR79 
PIR8001 PIR8002 
COR80 
PIU104 
PIU109 
PIU1010 
PIU1011 
PIU1012 
PIU1013 
PIU1014 
PIU1015 
PIU1016 
PIU1017 
PIU1018 
PIU1019 
PIU1020 PIU1022 
PIU1024 
PIU1025 PIU1026 
PIU1027 
PIU1029 
PIU1030 
COU1A 
PIU101 
PIU102 
PIU103 
PIU105 
PIU106 
PIU107 
PIU108 
PIU1021 
PIU1023 
PIU1028 
COU1B 
PIU201 
PIU202 
PIU203 
PIU204 
PIU205 
PIU206 PIU207 
PIU208 
COU2 
PIU1701 
PIU1702 
PIU1703 
PIU1704 
PIU1705 
PIU1706 PIU1707 
PIU1708 
COU17 
PIU1804 
PIU1809 
PIU18010 
PIU18011 
PIU18012 
PIU18013 
PIU18014 
PIU18015 
PIU18016 
PIU18017 
PIU18018 
PIU18019 
PIU18020 PIU18022 
PIU18024 
PIU18025 PIU18026 
PIU18027 
PIU18029 
PIU18030 
COU18A 
PIU1801 
PIU1802 
PIU1803 
PIU1805 
PIU1806 
PIU1807 
PIU1808 
PIU18021 
PIU18023 
PIU18028 
COU18B 
PIU1901 
PIU1902 
PIU1903 
PIU1904 
PIU1905 
PIU1906 PIU1907 
PIU1908 
COU19 



1
1
2
2
3
3
4
4
5
5
6
6
D D
C C
B B
A A
timingcard.com
*SHEET OF 8
Cannot open file 
C:\Users\<user>\Desktop\Ti
mecard 
Logo\TIMECARD.jpg.  
File does not exist.
REV DATEP3 09/14/21
GND GND
+12V_PCIE+3.3V_PCIE
+3.3V
+3.3V_PCIE
+12V_PCIE
PCIE_RX0_P
PCIE_RX0_N
PCIE_RX1_P
PCIE_RX1_N
PCIE_RX2_P
PCIE_RX2_N
PCIE_RX3_P
PCIE_RX3_N
PCIE_PERST
PCIE_CLK_P
PCIE_CLK_N
PCIE_TX0_P
PCIE_TX0_N
PCIE_TX1_P
PCIE_TX1_N
PCIE_TX2_P
PCIE_TX2_N
PCIE_TX3_P
PCIE_TX3_N
PCIe Connector
4.7K
R22
0.1UFC53
0.1UFC52
0 OHM
R24
0 OHM
R23
0.1UFC51
0.1UFC49
0.1UFC47
0.1UFC45
0.1UFC44
0.1UFC46
0.1UFC48
0.1UFC50
KEY KEY
+12v1B1
+12V2B2
+12V3B3
GND1B4
SMCLKB5
SMDATAB6
GND2B7
+3.3V1B8
JTAG/TRST_nB9
+3.3vauxB10
WAKE_nB11
RESERVED1B12
GND3B13
PETp0B14
PETn0B15
GND4B16
PRSNT2_nB17
GND5B18
PETp1B19
PETn1B20
GND6B21
GND7B22
PETp2B23
PETn2B24
GND8B25
GND9B26
PETp3B27
PETn3B28
GND10B29
RESERVED2B30
PRSNT4_nB31
GND11B32
PRSNT1_n A1
+12V5 A2
+12V4 A3
GND37 A4
JTAG/TCK A5
JTAG/TDI A6
JTAG/TDO A7
JTAG/TMS A8
+3.3V3 A9
+3.3V2 A10
PERST A11
GND36 A12
REFCLK+ A13
REFCLK- A14
GND35 A15
PERp0 A16
PERn0 A17
GND34 A18
RESERVED5 A19
GND33 A20
PERp1 A21
PERn1 A22
GND32 A23
GND31 A24
PERp2 A25
PERn2 A26
GND30 A27
GND29 A28
PERp3 A29
PERn3 A30
GND28 A31
RESERVED4 A32
P2
PCIex4
GND
+3.3V
GND GND GND GND+3.3V +3.3V +3.3V +3.3V
FPGA_TCK
FPGA_TDO
FPGA_TMS
FPGA_TDI
JTAG
33 OHM
R18
33 OHM
R19
33 OHM
R20
33 OHM
R21
2X5
9
3
10
4
1
5
7
2
6
8
U5
BAT54SW
2
3
1
D8
BAT54SW
2
3
1
D7
BAT54SW
2
3
1
D6
BAT54SW
2
3
1
D5
PRSNT
PRSNT
PRSNT
FPGA_TCK FPGA_TDO FPGA_TMS FPGA_TDI
PIC4401 PIC4402 
COC44 
PIC4501 PIC4502 
COC45 
PIC4601 PIC4602 
COC46 
PIC4701 PIC4702 
COC47 
PIC4801 PIC4802 
COC48 
PIC4901 PIC4902 
COC49 
PIC5001 PIC5002 
COC50 
PIC5101 PIC5102 
COC51 
PIC5201 PIC5202 
COC52 
PIC5301 PIC5302 
COC53 
PID501 PID502 
PID503 
COD5 
PID601 PID602 
PID603 
COD6 
PID701 PID702 
PID703 
COD7 
PID801 PID802 
PID803 
COD8 
PIP20A1 
PIP20A2 
PIP20A3 
PIP20A4 
PIP20A5 
PIP20A6 
PIP20A7 
PIP20A8 
PIP20A9 
PIP20A10 
PIP20A11 
PIP20A12 
PIP20A13 
PIP20A14 
PIP20A15 
PIP20A16 
PIP20A17 
PIP20A18 
PIP20A19 
PIP20A20 
PIP20A21 
PIP20A22 
PIP20A23 
PIP20A24 
PIP20A25 
PIP20A26 
PIP20A27 
PIP20A28 
PIP20A29 
PIP20A30 
PIP20A31 
PIP20A32 
PIP20B1 
PIP20B2 
PIP20B3 
PIP20B4 
PIP20B5 
PIP20B6 
PIP20B7 
PIP20B8 
PIP20B9 
PIP20B10 
PIP20B11 
PIP20B12 
PIP20B13 
PIP20B14 
PIP20B15 
PIP20B16 
PIP20B17 
PIP20B18 
PIP20B19 
PIP20B20 
PIP20B21 
PIP20B22 
PIP20B23 
PIP20B24 
PIP20B25 
PIP20B26 
PIP20B27 
PIP20B28 
PIP20B29 
PIP20B30 
PIP20B31 
PIP20B32 
COP2 
PIR1801 PIR1802 
COR18 
PIR1901 PIR1902 
COR19 
PIR2001 PIR2002 
COR20 
PIR2101 PIR2102 
COR21 
PIR2201 
PIR2202 
COR22 
PIR2301 PIR2302 
COR23 
PIR2401 PIR2402 
COR24 
PIU501 PIU502 
PIU503 PIU504 
PIU505 PIU506 
PIU507 PIU508 
PIU509 PIU5010 
COU5 



1
1
2
2
3
3
4
4
5
5
6
6
D D
C C
B B
A A
timingcard.com
*SHEET OF 8
Cannot open file 
C:\Users\<user>\Desktop\Ti
mecard 
Logo\TIMECARD.jpg.  
File does not exist.
REV DATEP3 09/14/21
+5.0V
GND
+3.3V
GND GND
GPS1_TP2
GPS1_TP1
GPS1_RX
GPS1_TX
GPS1_RST
GPS
VCC_ANT1
VCC2
TXD3
RST4 RXD 5TP1 6TP2 7GND 8
U9
RCB-F9T VCC4 SCL 1
SDA 3
WP5 GND 2
U7
AT24MAC402-STUM-T
SDA
SCL
+3.3V
GND
C59
0.1uF
C61
0.1uF
C25
0.1uF
+3.3V
GND
EXT_EEPROM_WP
R37
10K
EEPROM
VDD8
VDDIO6
CS 2
SCK 4
SDI 3
SDO 5
GND 1
GND 7
U14
BME280
GNDGND
C31
0.1uF
C30
0.1uF
+3.3V+3.3V
SCL
SDA
+3.3V
GND GND
ENVIRONMENT (0x76)
IMU (0x29)
SCLSDA
+3.3V+3.3V
R27
4.7K
R26
4.7K
+5.0V
GND
+3.3V
GND GND
GPS2_TP2
GPS2_TP1
GPS2_RX
GPS2_TX
GPS2_RST
VCC_ANT1
VCC2
TXD3
RST4 RXD 5TP1 6TP2 7GND 8
U15
RCB-F9T-1
C36
0.1uF
C37
0.1uF
12
C58
10uF
12
C60
10uF
12
C34
10uF
12
C35
10uF
1
2
3
4
5
6
7
8
9
10
11
12
P3
EXT GPIO
+3.3V
GNDGND
+3.3V
EXT_GPIO_1
EXT_GPIO_2
EXT_GPIO_3
EXT_GPIO_4
EXT_GPIO_7
EXT_GPIO_8
EXT_GPIO_9
EXT_GPIO_10
EXTERNAL GPIO
36-24393-ND
J5
GNSS Standoff
36-24393-ND
J7
GNSS Standoff
36-24393-ND
J8
GNSS Standoff
36-24393-ND
J9
GNSS Standoff
36-24393-ND
J10
GNSS Standoff
36-24393-ND
J11
GNSS Standoff
36-24393-ND
J12
GNSS Standoff
36-24393-ND
J14
GNSS Standoff
335-1156-ND
J15
M3 screw
335-1156-ND
J16
M3 screw
335-1156-ND
J17
M3 screw
335-1156-ND
J18
M3 screw
335-1156-ND
J19
M3 screw
335-1156-ND
J20
M3 screw
335-1156-ND
J21
M3 screw
335-1156-ND
J22
M3 screw
335-1156-ND
J23
M3 screw
335-1156-ND
J24
M3 screw
335-1156-ND
J25
M3 screw
335-1156-ND
J26
M3 screw
335-1156-ND
J27
M3 screw
335-1156-ND
J28
M3 screw
335-1156-ND
J29
M3 screw
335-1156-ND
J30
M3 screw
335-1156-ND
J32
M3 screw
335-1156-ND
J33
M3 screw
PCIe Bracket screws
1
2
3
4
5
P1
TSW-105-05-L-S
+3.3V
GND
SCL
SDA
MAC_FREQ_CTRLR48 0_1%_0402
Allow DAC daughter card to control atomic clock analog input
11
22
33
44
5 5
6 6
7 7
8 8
99
1010
1111
1212
13 13
14 14
15 15
16 16
SAM11878-ND
J6
GNSS Header 16-pin
11
22
33
44
5 5
6 6
7 7
8 8
99
1010
1111
1212
13 13
14 14
15 15
16 16
SAM11878-ND
J13
GNSS Header 16-pin
+5.0V+3.3V
GND GND
C57
0.1uF
C64
0.1uF
12
C55
10uF
12
C56
10uF
GND
GND
+5.0V+3.3V
GND GND
C43
0.1uF
C54
0.1uF
12
C41
10uF
12
C42
10uF
GPS1_PIN11
GPS1_PIN12
GPS1_PIN13
GPS1_PIN14
GPS1_PIN15
GPS2_PIN11
GPS2_PIN12
GPS2_PIN13
GPS2_PIN14
GPS2_PIN15
VDD3
VDDIO28
NC1
SWDIO7
SWCLK8 BL IND 10
NC12
NC13
NC 15
NC 16
NC 21NC 22
NC23
NC24
PS06
PS15
BOOT LOAD PIN 4
RESET11
CAP 9
INT 14
XIN3227 XOUT32 26
COM0 20
COM1 19
COM2 18
COM3 17
GND 2
GNDIO 25
U13
BNO055
GND
+3.3V +3.3V
GND GND
+3.3V
GNDGND
SCL
SDA
+3.3V
PCIE_PERST R54 0_1%_0402
BNO_INT
BNO_INT
BNO_BLIND
BNO_XIN32
BNO_XOUT32
BNO_XIN32
BNO_XOUT32
BNO_XIN32_C
BNO_XOUT32_C
R57
4.7K_0402
R58
4.7K_0402
R53
4.7K_0402
R56
DNI_4.7K_0402
R52
4.7K_0402
R50
4.7K_0402
R51
4.7K_0402
R55
4.7K_0402
C66
0.1uF_0402
C67
0.1uF_0402
1 2
C65
1uF_0402
C32
0.1uF_0402
C33
0.1uF_0402
PIC2501 
PIC2502 
COC25 
PIC3001 
PIC3002 COC30 
PIC3101 
PIC3102 COC31 
PIC3201 PIC3202 
COC32 
PIC3301 PIC3302 
COC33 
PIC3401 
PIC3402 
COC34 PIC3501 
PIC3502 
COC35 
PIC3601 
PIC3602 COC36 
PIC3701 
PIC3702 COC37 
PIC4101 
PIC4102 COC41 PIC4201 
PIC4202 COC42 
PIC4301 
PIC4302 
COC43 
PIC5401 
PIC5402 
COC54 
PIC5501 
PIC5502 COC55 PIC5601 
PIC5602 COC56 
PIC5701 
PIC5702 
COC57 
PIC5801 
PIC5802 COC58 
PIC5901 
PIC5902 
COC59 
PIC6001 
PIC6002 COC60 
PIC6101 
PIC6102 
COC61 
PIC6401 
PIC6402 
COC64 
PIC6501 PIC6502 
COC65 
PIC6601 
PIC6602 
COC66 PIC6701 
PIC6702 
COC67 
COJ5 
PIJ601 
PIJ602 
PIJ603 
PIJ604 
PIJ605 
PIJ606 
PIJ607 
PIJ608 
PIJ609 
PIJ6010 
PIJ6011 
PIJ6012 
PIJ6013 
PIJ6014 
PIJ6015 
PIJ6016 
COJ6 
COJ7 
COJ8 
COJ9 
COJ10 
COJ11 
COJ12 
PIJ1301 
PIJ1302 
PIJ1303 
PIJ1304 
PIJ1305 
PIJ1306 
PIJ1307 
PIJ1308 
PIJ1309 
PIJ13010 
PIJ13011 
PIJ13012 
PIJ13013 
PIJ13014 
PIJ13015 
PIJ13016 
COJ13 
COJ14 
COJ15 
COJ16 
COJ17 
COJ18 
COJ19 
COJ20 
COJ21 
COJ22 
COJ23 
COJ24 
COJ25 
COJ26 
COJ27 
COJ28 
COJ29 
COJ30 
COJ32 COJ33 
PIP101 
PIP102 
PIP103 
PIP104 
PIP105 
COP1 
PIP301 
PIP302 
PIP303 
PIP304 
PIP305 
PIP306 
PIP307 
PIP308 
PIP309 
PIP3010 
PIP3011 
PIP3012 
COP3 
PIR2601 
PIR2602 COR26 
PIR2701 
PIR2702 COR27 
PIR3701 
PIR3702 
COR37 
PIR4801 PIR4802 
COR48 
PIR5001 PIR5002 
COR50 
PIR5101 PIR5102 
COR51 
PIR5201 PIR5202 
COR52 PIR5301 
PIR5302 
COR53 
PIR5401 PIR5402 
COR54 
PIR5501 PIR5502 
COR55 
PIR5601 
PIR5602 
COR56 
PIR5701 
PIR5702 
COR57 PIR5801 
PIR5802 
COR58 
PIU701 
PIU702 
PIU703 
PIU704 
PIU705 
COU7 
PIU901 
PIU902 
PIU903 
PIU904 PIU905 
PIU906 
PIU907 
PIU908 
COU9 
PIU1301 
PIU1302 
PIU1303 PIU1304 
PIU1305 
PIU1306 
PIU1307 
PIU1308 
PIU1309 
PIU13010 
PIU13011 
PIU13012 
PIU13013 
PIU13014 
PIU13015 
PIU13016 
PIU13017 
PIU13018 
PIU13019 
PIU13020 
PIU13021 
PIU13022 
PIU13023 
PIU13024 
PIU13025 
PIU13026 
PIU13027 
PIU13028 
COU13 
PIU1401 
PIU1402 
PIU1403 
PIU1404 
PIU1405 
PIU1406 
PIU1407 
PIU1408 
COU14 
PIU1501 
PIU1502 
PIU1503 
PIU1504 PIU1505 
PIU1506 
PIU1507 
PIU1508 
COU15 



1
1
2
2
3
3
4
4
5
5
6
6
D D
C C
B B
A A
timingcard.com
*SHEET OF 8
Cannot open file 
C:\Users\<user>\Desktop\Ti
mecard 
Logo\TIMECARD.jpg.  
File does not exist.
REV DATEP3 09/14/21
MAC_TX
MAC_RX
MAC_BITEMAC_RF_OUT
MAC_FREQ_CTRL
FPGA_MAC_PPS_DIFF_IN0
MAC_USB+
MAC_USB-
MAC_USB_PWR
MAC_PPS_OUT+
MAC_PPS_OUT-
MAC_ALARM
GND
GND
GND
MAC
10uF
C62
FREQ CTRL INP1
GND (CASE)P2
RF OUTP3
GND (SUPPLY & SIGNAL)P4 VCC P5BITE P6RS-232 TX P7RS-232 RX P8
RV-3049-C3
PPS-IN P9
PPS-OUT P10
U10A
RV-3049-C3
PPS-IN 1+1 USB DATA + 2
PPS-IN 1-3 USB DATA - 4
PPS-IN 0+5 USB POWER 6
PPS-IN 0-7
GND 8
GND 9
NC10
NC11
NC12
NC13
NC14
GND 15NC16
PPS-OUT + 17
NC18
PPS-OUT - 19
ALARM 20
U10B
C63
0.1uF
DI12
DI23
DO+1 7
DO+2 6
DO-1 8
DO-2 5
GND 4VCC1
U3
DS90LV027AQMA
RIN1-1 RIN1+2
RIN2+3
RIN2-4
GND 5
ROUT2 6
ROUT1 7
VCC8
U4
DS90LV028AQMA
R11
4.7K
R10
4.7K C23
0.1uF
GNDGNDGND
+3.3V
MAC_PPS_IN1-
MAC_PPS_IN1+
MAC_PPS_IN0-
MAC_PPS_IN0+
GND
MAC_PPS_IN1-
MAC_PPS_IN1+
MAC_PPS_IN0-
MAC_PPS_IN0+
R12
110R
C24
0.1uF
+3.3V
GND GND
FPGA_MAC_PPSDIFF_OUT
MAC_PPS_OUT+
MAC_PPS_OUT-
FPGA_MAC_PPS_IN1-
MAC_PPS_IN
MAC_PPS_OUT
11
33
55
77
1010
1111
1212
1313
1414
1616
1818
WM24007CT-ND
2 2
4 4
6 6
17 17
19 19
20 20
8 8
9 9
15 15
J31
SA53_Header
GND
R45
0_5%_1206
R46
DNI_0_5%_1206
+5.0V +12V
12V and 3.3V Option for different Atomic clocks
MAC_VCC
R47
DNI_0_5%_1206
+3.3V
1
SKT2
0332-0-43-80-18-27-10-0
1
SKT5
0332-0-43-80-18-27-10-0
1
SKT6
0332-0-43-80-18-27-10-0
1
SKT9
0332-0-43-80-18-27-10-0
1
SKT1
0332-0-43-80-18-27-10-0
1
SKT3
0332-0-43-80-18-27-10-0
1
SKT4
0332-0-43-80-18-27-10-0
1
SKT7
0332-0-43-80-18-27-10-01
SKT8
0332-0-43-80-18-27-10-0
1
SKT10
0332-0-43-80-18-27-10-0
H700-ND
J39
SA53 Screw
H700-ND
J41
SA53 Screw
H700-ND
J40
SA53 Screw
H700-ND
J42
SA53 Screw
PIC2301 
PIC2302 COC23 
PIC2401 
PIC2402 
COC24 
PIC6201 
PIC6202 
COC62 
PIC6301 
PIC6302 COC63 
PIJ3101 PIJ3102 
PIJ3103 PIJ3104 
PIJ3105 PIJ3106 
PIJ3107 
PIJ3108 
PIJ3109 
PIJ31010 
PIJ31011 
PIJ31012 
PIJ31013 
PIJ31014 
PIJ31015 
PIJ31016 
PIJ31017 
PIJ31018 
PIJ31019 
PIJ31020 
COJ31 
COJ39 COJ40 
COJ41 COJ42 
PIR1001 
PIR1002 
COR10 
PIR1101 
PIR1102 
COR11 
PIR1201 
PIR1202 
COR12 
PIR4501 PIR4502 
COR45 
PIR4601 PIR4602 
COR46 
PIR4701 PIR4702 
COR47 
PISKT101 
COSKT1 
PISKT201 
COSKT2 
PISKT301 
COSKT3 
PISKT401 
COSKT4 
PISKT501 
COSKT5 
PISKT601 
COSKT6 
PISKT701 
COSKT7 
PISKT801 
COSKT8 
PISKT901 
COSKT9 
PISKT1001 
COSKT10 
PIU301 
PIU302 
PIU303 
PIU304 
PIU305 
PIU306 
PIU307 
PIU308 
COU3 
PIU401 
PIU402 
PIU403 
PIU404 
PIU405 
PIU406 
PIU407 
PIU408 
COU4 
PIU100P1 
PIU100P2 
PIU100P3 
PIU100P4 PIU100P5 
PIU100P6 
PIU100P7 
PIU100P8 
PIU100P9 
PIU100P10 
COU10A 
PIU1001 PIU1002 
PIU1003 PIU1004 
PIU1005 PIU1006 
PIU1007 
PIU1008 
PIU1009 
PIU10010 
PIU10011 
PIU10012 
PIU10013 
PIU10014 
PIU10015 
PIU10016 
PIU10017 
PIU10018 
PIU10019 
PIU10020 
COU10B 



1
1
2
2
3
3
4
4
5
5
6
6
D D
C C
B B
A A
timingcard.com
*SHEET OF 8
Cannot open file 
C:\Users\<user>\Desktop\Ti
mecard 
Logo\TIMECARD.jpg.  
File does not exist.
REV DATEP3 09/14/21
+5.0V
GND
KEY2
LED4
LED3
LED2
LED1
+5.0V
GND
GPS1_RST
GPS1_TP1
GPS1_TP2
GND
GPS1_RX
MAC_ALARM
MAC_BITE
MAC_FREQ_CTRL
FPGA_MAC_PPS_IN0-
FPGA_MAC_PPS_IN1-
FPGA_MAC_PPS_OUT-
MAC_RF_OUT
SDA
SCL
GND
GPS1_TX
MAC_RX
MAC_TX
MAC_USB+
MAC_USB-
MAC_USB_PWR
GND
PCIE_PERST
KEY1
FPGA_TCK
FPGA_TDO
GND
FPGA_TDI
FPGA_TMS
GND
PCIE_TX3_P
PCIE_TX3_N
PCIE_RX3_P
PCIE_RX3_N
PCIE_TX0_P
PCIE_TX0_N
PCIE_RX0_P
PCIE_RX0_N
GND
PCIE_TX2_P
PCIE_TX2_N
PCIE_RX2_P
PCIE_RX2_N
PCIE_TX1_P
PCIE_TX1_N
PCIE_RX1_P
PCIE_RX1_N
PCIE_CLK_P
PCIE_CLK_N
UART1_TXD
UART1_RXD
IO_LED1
IO_LED2
IO_LED3
IO_LED4
GPS2_RX_FPGAGPS2_TX_FPGA
GPS2_TP2
GPS2_TP1
GPS2_RST
ANT1_IO_OUT
ANT1_IO_IN
ANT2_IO_OUT
ANT2_IO_IN
ANT3_IO_OUT
ANT3_IO_IN
ANT4_IO_OUT
ANT4_IO_IN
EXT_GPIO_7
EXT_GPIO_8
EXT_GPIO_9
EXT_GPIO_10
EXT_GPIO_1
EXT_GPIO_2
EXT_GPIO_3
EXT_GPIO_4
ANT1_OUT
ANT1_IN
ANT2_OUT
ANT2_IN
ANT3_OUT
ANT3_IN
ANT4_OUT
ANT4_IN
EXT_EEPROM_WP
AXK680347YG
11 2 2
33 4 4
55 6 6
77 8 8
99 10 10
1111 12 12
1313 14 14
1515 16 16
1717 18 18
1919 20 20
2121 22 22
2323 24 24
2525 26 26
2727 28 28
2929 30 30
3131 32 32
3333 34 34
3535 36 36
3737 38 38
3939 40 40
4141 42 42
4343 44 44
4545 46 46
4747 48 48
4949 50 50
5151 52 52
5353 54 54
5555 56 56
5757 58 58
5959 60 60
6161 62 62
6363 64 64
6565 66 66
6767 68 68
6969 70 70
7171 72 72
7373 74 74
7575 76 76
7777 78 78
7979 80 80
8181 82 82
8383 84 84
J34
Single FPGA Conn
AXK680347YG
11 2 2
33 4 4
55 6 6
77 8 8
99 10 10
1111 12 12
1313 14 14
1515 16 16
1717 18 18
1919 20 20
2121 22 22
2323 24 24
2525 26 26
2727 28 28
2929 30 30
3131 32 32
3333 34 34
3535 36 36
3737 38 38
3939 40 40
4141 42 42
4343 44 44
4545 46 46
4747 48 48
4949 50 50
5151 52 52
5353 54 54
5555 56 56
5757 58 58
5959 60 60
6161 62 62
6363 64 64
6565 66 66
6767 68 68
6969 70 70
7171 72 72
7373 74 74
7575 76 76
7777 78 78
7979 80 80
8181 82 82
8383 84 84
J36
Single FPGA Conn
AXK680347YG
11 2 2
33 4 4
55 6 6
77 8 8
99 10 10
1111 12 12
1313 14 14
1515 16 16
1717 18 18
1919 20 20
2121 22 22
2323 24 24
2525 26 26
2727 28 28
2929 30 30
3131 32 32
3333 34 34
3535 36 36
3737 38 38
3939 40 40
4141 42 42
4343 44 44
4545 46 46
4747 48 48
4949 50 50
5151 52 52
5353 54 54
5555 56 56
5757 58 58
5959 60 60
6161 62 62
6363 64 64
6565 66 66
6767 68 68
6969 70 70
7171 72 72
7373 74 74
7575 76 76
7777 78 78
7979 80 80
8181 82 82
8383 84 84
J35
Single FPGA Conn
AXK680347YG
11 2 2
33 4 4
55 6 6
77 8 8
99 10 10
1111 12 12
1313 14 14
1515 16 16
1717 18 18
1919 20 20
2121 22 22
2323 24 24
2525 26 26
2727 28 28
2929 30 30
3131 32 32
3333 34 34
3535 36 36
3737 38 38
3939 40 40
4141 42 42
4343 44 44
4545 46 46
4747 48 48
4949 50 50
5151 52 52
5353 54 54
5555 56 56
5757 58 58
5959 60 60
6161 62 62
6363 64 64
6565 66 66
6767 68 68
6969 70 70
7171 72 72
7373 74 74
7575 76 76
7777 78 78
7979 80 80
8181 82 82
8383 84 84
J37
Single FPGA Conn
R49 0_1%_0402
GPS1_PIN15
GPS1_PIN14
GPS1_PIN12
GPS1_PIN13
GPS1_PIN11
GPS2_PIN15
GPS2_PIN13
GPS2_PIN11 GPS2_PIN12
GPS2_PIN14
BNO_INT
BNO_XOUT32_C
BNO_XIN32_C
PIJ3401 PIJ3402 
PIJ3403 PIJ3404 
PIJ3405 PIJ3406 
PIJ3407 PIJ3408 
PIJ3409 PIJ34010 
PIJ34011 PIJ34012 
PIJ34013 PIJ34014 
PIJ34015 PIJ34016 
PIJ34017 PIJ34018 
PIJ34019 PIJ34020 
PIJ34021 PIJ34022 
PIJ34023 PIJ34024 
PIJ34025 PIJ34026 
PIJ34027 PIJ34028 
PIJ34029 PIJ34030 
PIJ34031 PIJ34032 
PIJ34033 PIJ34034 
PIJ34035 PIJ34036 
PIJ34037 PIJ34038 
PIJ34039 PIJ34040 
PIJ34041 PIJ34042 
PIJ34043 PIJ34044 
PIJ34045 PIJ34046 
PIJ34047 PIJ34048 
PIJ34049 PIJ34050 
PIJ34051 PIJ34052 
PIJ34053 PIJ34054 
PIJ34055 PIJ34056 
PIJ34057 PIJ34058 
PIJ34059 PIJ34060 
PIJ34061 PIJ34062 
PIJ34063 PIJ34064 
PIJ34065 PIJ34066 
PIJ34067 PIJ34068 
PIJ34069 PIJ34070 
PIJ34071 PIJ34072 
PIJ34073 PIJ34074 
PIJ34075 PIJ34076 
PIJ34077 PIJ34078 
PIJ34079 PIJ34080 
PIJ34081 PIJ34082 
PIJ34083 PIJ34084 
COJ34 
PIJ3501 PIJ3502 
PIJ3503 PIJ3504 
PIJ3505 PIJ3506 
PIJ3507 PIJ3508 
PIJ3509 PIJ35010 
PIJ35011 PIJ35012 
PIJ35013 PIJ35014 
PIJ35015 PIJ35016 
PIJ35017 PIJ35018 
PIJ35019 PIJ35020 
PIJ35021 PIJ35022 
PIJ35023 PIJ35024 
PIJ35025 PIJ35026 
PIJ35027 PIJ35028 
PIJ35029 PIJ35030 
PIJ35031 PIJ35032 
PIJ35033 PIJ35034 
PIJ35035 PIJ35036 
PIJ35037 PIJ35038 
PIJ35039 PIJ35040 
PIJ35041 PIJ35042 
PIJ35043 PIJ35044 
PIJ35045 PIJ35046 
PIJ35047 PIJ35048 
PIJ35049 PIJ35050 
PIJ35051 PIJ35052 
PIJ35053 PIJ35054 
PIJ35055 PIJ35056 
PIJ35057 PIJ35058 
PIJ35059 PIJ35060 
PIJ35061 PIJ35062 
PIJ35063 PIJ35064 
PIJ35065 PIJ35066 
PIJ35067 PIJ35068 
PIJ35069 PIJ35070 
PIJ35071 PIJ35072 
PIJ35073 PIJ35074 
PIJ35075 PIJ35076 
PIJ35077 PIJ35078 
PIJ35079 PIJ35080 
PIJ35081 PIJ35082 
PIJ35083 PIJ35084 
COJ35 
PIJ3601 PIJ3602 
PIJ3603 PIJ3604 
PIJ3605 PIJ3606 
PIJ3607 PIJ3608 
PIJ3609 PIJ36010 
PIJ36011 PIJ36012 
PIJ36013 PIJ36014 
PIJ36015 PIJ36016 
PIJ36017 PIJ36018 
PIJ36019 PIJ36020 
PIJ36021 PIJ36022 
PIJ36023 PIJ36024 
PIJ36025 PIJ36026 
PIJ36027 PIJ36028 
PIJ36029 PIJ36030 
PIJ36031 PIJ36032 
PIJ36033 PIJ36034 
PIJ36035 PIJ36036 
PIJ36037 PIJ36038 
PIJ36039 PIJ36040 
PIJ36041 PIJ36042 
PIJ36043 PIJ36044 
PIJ36045 PIJ36046 
PIJ36047 PIJ36048 
PIJ36049 PIJ36050 
PIJ36051 PIJ36052 
PIJ36053 PIJ36054 
PIJ36055 PIJ36056 
PIJ36057 PIJ36058 
PIJ36059 PIJ36060 
PIJ36061 PIJ36062 
PIJ36063 PIJ36064 
PIJ36065 PIJ36066 
PIJ36067 PIJ36068 
PIJ36069 PIJ36070 
PIJ36071 PIJ36072 
PIJ36073 PIJ36074 
PIJ36075 PIJ36076 
PIJ36077 PIJ36078 
PIJ36079 PIJ36080 
PIJ36081 PIJ36082 
PIJ36083 PIJ36084 
COJ36 
PIJ3701 PIJ3702 
PIJ3703 PIJ3704 
PIJ3705 PIJ3706 
PIJ3707 PIJ3708 
PIJ3709 PIJ37010 
PIJ37011 PIJ37012 
PIJ37013 PIJ37014 
PIJ37015 PIJ37016 
PIJ37017 PIJ37018 
PIJ37019 PIJ37020 
PIJ37021 PIJ37022 
PIJ37023 PIJ37024 
PIJ37025 PIJ37026 
PIJ37027 PIJ37028 
PIJ37029 PIJ37030 
PIJ37031 PIJ37032 
PIJ37033 PIJ37034 
PIJ37035 PIJ37036 
PIJ37037 PIJ37038 
PIJ37039 PIJ37040 
PIJ37041 PIJ37042 
PIJ37043 PIJ37044 
PIJ37045 PIJ37046 
PIJ37047 PIJ37048 
PIJ37049 PIJ37050 
PIJ37051 PIJ37052 
PIJ37053 PIJ37054 
PIJ37055 PIJ37056 
PIJ37057 PIJ37058 
PIJ37059 PIJ37060 
PIJ37061 PIJ37062 
PIJ37063 PIJ37064 
PIJ37065 PIJ37066 
PIJ37067 PIJ37068 
PIJ37069 PIJ37070 
PIJ37071 PIJ37072 
PIJ37073 PIJ37074 
PIJ37075 PIJ37076 
PIJ37077 PIJ37078 
PIJ37079 PIJ37080 
PIJ37081 PIJ37082 
PIJ37083 PIJ37084 
COJ37 
PIR4901 PIR4902 
COR49 



1
1
2
2
3
3
4
4
5
5
6
6
D D
C C
B B
A A
Title
Number RevisionSize
B
Date: 1/27/2023 Sheet   of
File: C:\Users\<user>\08-USBUart_DipSelects.SchDocDrawn By:
3V3OUT3
VCC4
VCCIO9
CTS 11
RESET2
RTS 8
CBUS0 6
RXD 10TXD 7
USBDM1
USBDP12
GND 5
GND 13
U20
FT234XD-R
VBUS
D-
D+
ID
GND
MNT 1
MNT 2
MNT 3
MNT 4
1
2
3
4
5
6
7
8
9
J43
2049261103
12
C86
10nF_50V_0402
1 2
FB1
600ohm_1.3A_0603
GND
FTDI_USB_R_N
FTDI_USB_R_P
12
C92
0.1uF_25V_0402
R81 27_1%_0402
R43 27_1%_0402 FTDI_USB_N
FTDI_USB_P
FTDI_VBUSUSB_VBUS
GND
GND
R82
10K_1%_0402
GND
12
C91
10nF_50V_0402
R13 27_1%_0402
R42 27_1%_0402 FTDI_TX
FTDI_RX
12
C89
0.1uF_25V_0402
12
C90
4.7uF_16V_0402
12
C93
0.1uF_25V_0402
USB to UART
1
2 3
4
SW1
A6H-2102
DIP Switch, Configure UART and PPS Single ended versus differential
GND
DIP_SW_UART_SEL
DIP_SW_PPS_SEL
UART either goes to FPGA or to GPS2
R88
10K_1%_0402
+3.3V
R89
10K_1%_0402
+3.3V
VCC9
SEL11
SEL25
NO12
NO24
COM1 11
COM2 7
FLT12
OE6
NC110
NC28
GND 3
U22
TMUX1072RUTR
GND
12
C95
0.1uF_25V_0402
+3.3V
GND
Select GPS Uart, either FTDI or FPGA
DIP_SW_UART_SEL
GND
R90 27_1%_0402
R92 27_1%_0402
GPS2_RX_FPGA
GPS2_TX_FPGA
FTDI_TX
FTDI_RX
GPS2_RX
GPS2_TX
R93 27_1%_0402
R91 27_1%_0402
VCC9
SEL11
SEL25
NO12
NO24
COM1 11
COM2 7
FLT12
OE6
NC110
NC28
GND 3
U21
TMUX1072RUTR
GND
12
C94
0.1uF_25V_0402
+3.3V
GND
Connect FTDI to FPGA otherwise
DIP_SW_UART_SEL
GND
R84 27_1%_0402
R86 27_1%_0402
R87 27_1%_0402
R85 27_1%_0402
UART1_TXD
UART1_RXD
GND
GND
FTDI_TX
FTDI_RX
VCC9
SEL11
SEL25
NO12
NO24
COM1 11
COM2 7
FLT12
OE6
NC110
NC28
GND 3
U23
TMUX1072RUTR
GND
12
C96
0.1uF_25V_0402
+3.3V
GND
Atomic clock PPS input / output select
DIP_SW_PPS_SEL
GND
MAC_PPS_OUTSingle ended PPS output R96 49.9_1%_0402 FPGA_MAC_PPS_OUT- FPGA Single ended PPS Input
FPGA_MAC_PPSDIFF_OUT R97 49.9_1%_0402Diff PPS Output
MAC_PPS_IN R98 49.9_1%_0402
R99 49.9_1%_0402
Single ended PPS input
FPGA_MAC_PPS_DIFF_IN0Single ended to diff PPS input
FPGA_MAC_PPS_IN0- FPGA Single ended PPS Output
+3.3V21
D24
SML-LX0603IW-TR
1 2
R94
200_1%_0402
DIP_SW_PPS_SEL
+3.3V21
D25
SML-LX0603IW-TR
1 2
R95
200_1%_0402
DIP_SW_UART_SEL
Status LEDs
UART_SEL = 0 for FTDI <-> GPS2, 1 for FTDI <-> FPGA and FPGA <-> GPS2
PPS_SEL = 0 for Single Ended PPS, 1 for Differential PPS (SA53)
PPS_SEL = 0 for Single Ended PPS, 1 for Differential PPS (SA53) UART_SEL = 0 for FTDI <-> GPS2, 1 for FTDI <-> FPGA and FPGA <-> GPS2
R102DNI_27_1%_0402
R103DNI_27_1%_0402GPS2_RX_FPGA
GPS2_TX_FPGA
R100DNI_27_1%_0402
R101DNI_27_1%_0402
FTDI_RX
FTDI_TX
R107 DNI_49.9_1%_0402
R105 DNI_49.9_1%_0402
R104 DNI_49.9_1%_0402 MAC_PPS_OUT
R106 DNI_49.9_1%_0402 FPGA_MAC_PPSDIFF_OUT
MAC_PPS_IN
FPGA_MAC_PPS_DIFF_IN0
1 2
R83
15K_1%_0402
C87
47pF_50V_0402
C88
47pF_50V_0402
PIC8601 
PIC8602 COC86 
PIC8701 
PIC8702 
COC87 PIC8801 
PIC8802 
COC88 
PIC8901 
PIC8902 COC89 
PIC9001 
PIC9002 COC90 
PIC9101 
PIC9102 COC91 
PIC9201 
PIC9202 COC92 
PIC9301 
PIC9302 COC93 
PIC9401 
PIC9402 COC94 
PIC9501 
PIC9502 COC95 
PIC9601 
PIC9602 COC96 
PID2401 
PID2402 
COD24 
PID2501 
PID2502 
COD25 
PIFB101 PIFB102 
COFB1 
PIJ4301 
PIJ4302 
PIJ4303 
PIJ4304 
PIJ4305 
PIJ4306 
PIJ4307 
PIJ4308 
PIJ4309 
COJ43 
PIR1301 PIR1302 
COR13 
PIR4201 PIR4202 
COR42 
PIR4301 PIR4302 
COR43 
PIR8101 PIR8102 
COR81 
PIR8201 PIR8202 
COR82 
PIR8301 
PIR8302 
COR83 
PIR8401 PIR8402 
COR84 
PIR8501 PIR8502 
COR85 
PIR8601 PIR8602 
COR86 
PIR8701 PIR8702 
COR87 
PIR8801 
PIR8802 COR88 
PIR8901 
PIR8902 COR89 
PIR9001 PIR9002 
COR90 
PIR9101 PIR9102 COR91 
PIR9201 PIR9202 
COR92 
PIR9301 PIR9302 
COR93 
PIR9401 
PIR9402 
COR94 
PIR9501 
PIR9502 
COR95 
PIR9601 PIR9602 
COR96 
PIR9701 PIR9702 
COR97 
PIR9801 PIR9802 
COR98 
PIR9901 PIR9902 
COR99 
PIR10001 PIR10002 
COR100 
PIR10101 PIR10102 
COR101 
PIR10201 PIR10202 
COR102 
PIR10301 PIR10302 
COR103 
PIR10401 PIR10402 
COR104 
PIR10501 PIR10502 
COR105 
PIR10601 PIR10602 
COR106 
PIR10701 PIR10702 
COR107 
PISW101 
PISW102 PISW103 
PISW104 
COSW1 
PIU2001 
PIU2002 
PIU2003 
PIU2004 
PIU2005 
PIU2006 
PIU2007 
PIU2008 
PIU2009 PIU20010 
PIU20011 
PIU20012 
PIU20013 
COU20 
PIU2101 
PIU2102 
PIU2103 
PIU2104 
PIU2105 
PIU2106 
PIU2107 PIU2108 
PIU2109 
PIU21010 PIU21011 
PIU21012 
COU21 
PIU2201 
PIU2202 
PIU2203 
PIU2204 
PIU2205 
PIU2206 
PIU2207 PIU2208 
PIU2209 
PIU22010 PIU22011 
PIU22012 
COU22 
PIU2301 
PIU2302 
PIU2303 
PIU2304 
PIU2305 
PIU2306 
PIU2307 PIU2308 
PIU2309 
PIU23010 PIU23011 
PIU23012 
COU23 